(kicad_pcb
	(version 20241229)
	(generator "pcbnew")
	(generator_version "9.0")
	(general
		(thickness 1.63)
		(legacy_teardrops no)
	)
	(paper "A4")
	(title_block
		(title "CM4 Baseboard")
		(date "2026-01-05")
		(rev "1.1.1")
		(company "Antmicro Ltd")
		(comment 1 "www.antmicro.com")
		(comment 9 "footprints 291-295 of 506")
	)
	(layers
		(0 "F.Cu" signal)
		(4 "In1.Cu" power)
		(6 "In2.Cu" power)
		(8 "In3.Cu" signal)
		(10 "In4.Cu" signal)
		(2 "B.Cu" signal)
		(9 "F.Adhes" user "F.Adhesive")
		(11 "B.Adhes" user "B.Adhesive")
		(13 "F.Paste" user)
		(15 "B.Paste" user)
		(5 "F.SilkS" user "F.Silkscreen")
		(7 "B.SilkS" user "B.Silkscreen")
		(1 "F.Mask" user)
		(3 "B.Mask" user)
		(17 "Dwgs.User" user "User.Drawings")
		(19 "Cmts.User" user "User.Comments")
		(21 "Eco1.User" user "User.Eco1")
		(23 "Eco2.User" user "User.Eco2")
		(25 "Edge.Cuts" user)
		(27 "Margin" user)
		(31 "F.CrtYd" user "F.Courtyard")
		(29 "B.CrtYd" user "B.Courtyard")
		(35 "F.Fab" user)
		(33 "B.Fab" user)
	)
	(footprint "antmicro-footprints:LED_0603_1608Metric_G"
		(layer "F.Cu")
		(at 73.767962 160.8765 180)
		(descr "LED SMD 0603 Green")
		(tags "LED SMD 0603 Green")
		(property "Reference" "D306"
			(at 6.15 0.91 0)
			(layer "F.SilkS")
			(effects
				(font
					(size 0.7 0.7)
					(thickness 0.15)
				)
				(justify right bottom)
			)
		)
		(property "Value" "LED_G_0603_KP-1608CGCK"
			(at -0.001 1.599 0)
			(layer "F.Fab")
			(effects
				(font
					(size 0.7 0.7)
					(thickness 0.15)
				)
				(justify right bottom)
			)
		)
		(property "Datasheet" "http://www.kingbright.com/attachments/file/psearch//000/00/00/KP-1608CGCK(Ver.23B).pdf"
			(at 0 0 180)
			(layer "F.Fab")
			(hide yes)
			(effects
				(font
					(size 1.27 1.27)
					(thickness 0.15)
				)
			)
		)
		(property "MPN" "KP-1608CGCK"
			(at 0 0 180)
			(unlocked yes)
			(layer "F.Fab")
			(hide yes)
			(effects
				(font
					(size 1 1)
					(thickness 0.15)
				)
			)
		)
		(property "Manufacturer" "Kingbright"
			(at 0 0 180)
			(unlocked yes)
			(layer "F.Fab")
			(hide yes)
			(effects
				(font
					(size 1 1)
					(thickness 0.15)
				)
			)
		)
		(property "Color" "Green"
			(at 0 0 180)
			(unlocked yes)
			(layer "F.Fab")
			(hide yes)
			(effects
				(font
					(size 1 1)
					(thickness 0.15)
				)
			)
		)
		(property "Author" "Antmicro"
			(at 0 0 180)
			(unlocked yes)
			(layer "F.Fab")
			(hide yes)
			(effects
				(font
					(size 1 1)
					(thickness 0.15)
				)
			)
		)
		(property "License" "Apache-2.0"
			(at 0 0 180)
			(unlocked yes)
			(layer "F.Fab")
			(hide yes)
			(effects
				(font
					(size 1 1)
					(thickness 0.15)
				)
			)
		)
		(sheetname "/Supply/")
		(sheetfile "supply.kicad_sch")
		(attr smd)
		(fp_line
			(start 0.22 0.35)
			(end -0.22 0.35)
			(stroke
				(width 0.15)
				(type solid)
			)
			(layer "F.SilkS")
		)
		(fp_line
			(start 0.22 -0.35)
			(end -0.22 -0.35)
			(stroke
				(width 0.15)
				(type solid)
			)
			(layer "F.SilkS")
		)
		(fp_line
			(start 0.105328 0.201008)
			(end 0.105328 -0.198992)
			(stroke
				(width 0.1)
				(type solid)
			)
			(layer "F.SilkS")
		)
		(fp_line
			(start 0.105328 0.201008)
			(end -0.094672 0.001008)
			(stroke
				(width 0.1)
				(type solid)
			)
			(layer "F.SilkS")
		)
		(fp_line
			(start 0.105328 0.001008)
			(end 0.24 0.001)
			(stroke
				(width 0.1)
				(type solid)
			)
			(layer "F.SilkS")
		)
		(fp_line
			(start -0.094672 0.201008)
			(end -0.094672 -0.198992)
			(stroke
				(width 0.1)
				(type solid)
			)
			(layer "F.SilkS")
		)
		(fp_line
			(start -0.094672 0.001008)
			(end 0.105328 -0.198992)
			(stroke
				(width 0.1)
				(type solid)
			)
			(layer "F.SilkS")
		)
		(fp_line
			(start -0.094672 0.001008)
			(end -0.24 0.001008)
			(stroke
				(width 0.1)
				(type solid)
			)
			(layer "F.SilkS")
		)
		(fp_line
			(start -1.18 -0.319)
			(end -1.18 0.321)
			(stroke
				(width 0.15)
				(type solid)
			)
			(layer "F.SilkS")
		)
		(fp_rect
			(start 1.25 0.65)
			(end -1.25 -0.65)
			(stroke
				(width 0.05)
				(type solid)
			)
			(fill no)
			(layer "F.CrtYd")
		)
		(fp_line
			(start 0.599 0)
			(end 0.201 0)
			(stroke
				(width 0.15)
				(type solid)
			)
			(layer "F.Fab")
		)
		(fp_line
			(start 0.201 0.2)
			(end 0.201 0)
			(stroke
				(width 0.15)
				(type solid)
			)
			(layer "F.Fab")
		)
		(fp_line
			(start 0.201 0)
			(end 0.201 -0.202)
			(stroke
				(width 0.15)
				(type solid)
			)
			(layer "F.Fab")
		)
		(fp_line
			(start 0.201 -0.202)
			(end -0.101 0)
			(stroke
				(width 0.15)
				(type solid)
			)
			(layer "F.Fab")
		)
		(fp_line
			(start -0.101 0)
			(end 0.201 0.2)
			(stroke
				(width 0.15)
				(type solid)
			)
			(layer "F.Fab")
		)
		(fp_line
			(start -0.199 0.2)
			(end -0.199 0.1)
			(stroke
				(width 0.15)
				(type solid)
			)
			(layer "F.Fab")
		)
		(fp_line
			(start -0.199 0)
			(end -0.597 0)
			(stroke
				(width 0.15)
				(type solid)
			)
			(layer "F.Fab")
		)
		(fp_line
			(start -0.199 -0.202)
			(end -0.199 0.1)
			(stroke
				(width 0.15)
				(type solid)
			)
			(layer "F.Fab")
		)
		(fp_rect
			(start 0.848 0.4)
			(end -0.85 -0.402)
			(stroke
				(width 0.15)
				(type solid)
			)
			(fill no)
			(layer "F.Fab")
		)
		(fp_text user "License: Apache-2.0"
			(at -1.4224 3.599 180)
			(layer "F.Fab")
			(effects
				(font
					(size 0.7 0.7)
					(thickness 0.15)
				)
				(justify left bottom)
			)
		)
		(fp_text user "${REFERENCE}"
			(at -1.4224 5.999 180)
			(layer "F.Fab")
			(effects
				(font
					(size 0.7 0.7)
					(thickness 0.15)
				)
				(justify left bottom)
			)
		)
		(fp_text user "Author: Antmicro"
			(at -1.4224 4.799 180)
			(layer "F.Fab")
			(effects
				(font
					(size 0.7 0.7)
					(thickness 0.15)
				)
				(justify left bottom)
			)
		)
		(pad "1" smd roundrect
			(at -0.7 0)
			(size 0.8 1)
			(layers "F.Cu" "F.Mask" "F.Paste")
			(roundrect_rratio 0.2)
			(net 3 "GND")
			(pinfunction "C")
			(pintype "passive")
		)
		(pad "2" smd roundrect
			(at 0.7 0)
			(size 0.8 1)
			(layers "F.Cu" "F.Mask" "F.Paste")
			(roundrect_rratio 0.2)
			(net 476 "Net-(D306-A)")
			(pinfunction "A")
			(pintype "passive")
		)
	)
	(footprint "antmicro-footprints:R_0402_1005Metric"
		(layer "F.Cu")
		(at 54.827962 129.9265)
		(descr "Resistor SMD 0402")
		(tags "resistor SMD 0402")
		(property "Reference" "R410"
			(at -1.49 -5.38 0)
			(layer "F.SilkS")
			(effects
				(font
					(size 0.7 0.7)
					(thickness 0.15)
				)
				(justify left bottom)
			)
		)
		(property "Value" "R_10k_0402"
			(at -1.011843 1.772047 0)
			(layer "F.Fab")
			(effects
				(font
					(size 0.7 0.7)
					(thickness 0.15)
				)
				(justify left bottom)
			)
		)
		(property "Datasheet" "https://www.bourns.com/docs/product-datasheets/cr.pdf"
			(at 0 0 0)
			(layer "F.Fab")
			(hide yes)
			(effects
				(font
					(size 1.27 1.27)
					(thickness 0.15)
				)
			)
		)
		(property "Manufacturer" "Bourns"
			(at 0 0 0)
			(unlocked yes)
			(layer "F.Fab")
			(hide yes)
			(effects
				(font
					(size 1 1)
					(thickness 0.15)
				)
			)
		)
		(property "MPN" "CR0402-FX-1002GLF"
			(at 0 0 0)
			(unlocked yes)
			(layer "F.Fab")
			(hide yes)
			(effects
				(font
					(size 1 1)
					(thickness 0.15)
				)
			)
		)
		(property "Val" "10k"
			(at 0 0 0)
			(unlocked yes)
			(layer "F.Fab")
			(hide yes)
			(effects
				(font
					(size 1 1)
					(thickness 0.15)
				)
			)
		)
		(property "License" "Apache-2.0"
			(at 0 0 0)
			(unlocked yes)
			(layer "F.Fab")
			(hide yes)
			(effects
				(font
					(size 1 1)
					(thickness 0.15)
				)
			)
		)
		(property "Author" "Antmicro"
			(at 0 0 0)
			(unlocked yes)
			(layer "F.Fab")
			(hide yes)
			(effects
				(font
					(size 1 1)
					(thickness 0.15)
				)
			)
		)
		(property "Tolerance" "1%"
			(at 0 0 0)
			(unlocked yes)
			(layer "F.Fab")
			(hide yes)
			(effects
				(font
					(size 1 1)
					(thickness 0.15)
				)
			)
		)
		(sheetname "/Ethernet/")
		(sheetfile "ethernet.kicad_sch")
		(attr smd exclude_from_pos_files exclude_from_bom dnp)
		(fp_rect
			(start -0.925 -0.47)
			(end 0.925 0.47)
			(stroke
				(width 0.05)
				(type default)
			)
			(fill no)
			(layer "F.CrtYd")
		)
		(fp_rect
			(start -0.5 -0.25)
			(end 0.5 0.25)
			(stroke
				(width 0.15)
				(type solid)
			)
			(fill no)
			(layer "F.Fab")
		)
		(fp_text user "License: Apache-2.0"
			(at -0.95 5.169 0)
			(layer "F.Fab")
			(effects
				(font
					(size 0.7 0.7)
					(thickness 0.15)
				)
				(justify left bottom)
			)
		)
		(fp_text user "${REFERENCE}"
			(at -0.95 3.168 0)
			(layer "F.Fab")
			(effects
				(font
					(size 0.7 0.7)
					(thickness 0.15)
				)
				(justify left bottom)
			)
		)
		(fp_text user "Author: Antmicro"
			(at -0.95 4.169 0)
			(layer "F.Fab")
			(effects
				(font
					(size 0.7 0.7)
					(thickness 0.15)
				)
				(justify left bottom)
			)
		)
		(pad "1" smd roundrect
			(at -0.48 0)
			(size 0.59 0.64)
			(layers "F.Cu" "F.Mask" "F.Paste")
			(roundrect_rratio 0.25)
			(net 365 "/Ethernet/~{BT}")
			(pintype "passive")
		)
		(pad "2" smd roundrect
			(at 0.48 0)
			(size 0.59 0.64)
			(layers "F.Cu" "F.Mask" "F.Paste")
			(roundrect_rratio 0.25)
			(net 33 "/Ethernet/VDD")
			(pintype "passive")
		)
	)
	(footprint "antmicro-footprints:C_0402_1005Metric"
		(layer "F.Cu")
		(at 91.042962 144.282236 -90)
		(descr "Capacitor SMD 0402")
		(tags "capacitor SMD 0402")
		(property "Reference" "C917"
			(at -1.482236 0.422962 90)
			(layer "F.SilkS")
			(effects
				(font
					(size 0.7 0.7)
					(thickness 0.15)
				)
				(justify right bottom)
			)
		)
		(property "Value" "C_100n_0402"
			(at -1.022927 2.155213 90)
			(layer "F.Fab")
			(effects
				(font
					(size 0.7 0.7)
					(thickness 0.15)
				)
				(justify right bottom)
			)
		)
		(property "Datasheet" "https://www.murata.com/products/productdetail?partno=GRM155R61H104KE14%23"
			(at 0 0 270)
			(layer "F.Fab")
			(hide yes)
			(effects
				(font
					(size 1.27 1.27)
					(thickness 0.15)
				)
			)
		)
		(property "Manufacturer" "Murata"
			(at 0 0 270)
			(unlocked yes)
			(layer "F.Fab")
			(hide yes)
			(effects
				(font
					(size 1 1)
					(thickness 0.15)
				)
			)
		)
		(property "MPN" "GRM155R61H104KE14D"
			(at 0 0 270)
			(unlocked yes)
			(layer "F.Fab")
			(hide yes)
			(effects
				(font
					(size 1 1)
					(thickness 0.15)
				)
			)
		)
		(property "Val" "100n"
			(at 0 0 270)
			(unlocked yes)
			(layer "F.Fab")
			(hide yes)
			(effects
				(font
					(size 1 1)
					(thickness 0.15)
				)
			)
		)
		(property "License" "Apache-2.0"
			(at 0 0 270)
			(unlocked yes)
			(layer "F.Fab")
			(hide yes)
			(effects
				(font
					(size 1 1)
					(thickness 0.15)
				)
			)
		)
		(property "Author" "Antmicro"
			(at 0 0 270)
			(unlocked yes)
			(layer "F.Fab")
			(hide yes)
			(effects
				(font
					(size 1 1)
					(thickness 0.15)
				)
			)
		)
		(property "Voltage" "50V"
			(at 0 0 270)
			(unlocked yes)
			(layer "F.Fab")
			(hide yes)
			(effects
				(font
					(size 1 1)
					(thickness 0.15)
				)
			)
		)
		(property "Dielectric" "X5R"
			(at 0 0 270)
			(unlocked yes)
			(layer "F.Fab")
			(hide yes)
			(effects
				(font
					(size 1 1)
					(thickness 0.15)
				)
			)
		)
		(sheetname "/USB/")
		(sheetfile "usb.kicad_sch")
		(attr smd)
		(fp_rect
			(start -0.925 -0.47)
			(end 0.925 0.47)
			(stroke
				(width 0.05)
				(type default)
			)
			(fill no)
			(layer "F.CrtYd")
		)
		(fp_line
			(start -0.494 0.248)
			(end -0.494 -0.25)
			(stroke
				(width 0.15)
				(type solid)
			)
			(layer "F.Fab")
		)
		(fp_line
			(start 0.504 0.248)
			(end -0.494 0.248)
			(stroke
				(width 0.15)
				(type solid)
			)
			(layer "F.Fab")
		)
		(fp_line
			(start -0.494 -0.25)
			(end 0.504 -0.25)
			(stroke
				(width 0.15)
				(type solid)
			)
			(layer "F.Fab")
		)
		(fp_line
			(start 0.504 -0.25)
			(end 0.504 0.248)
			(stroke
				(width 0.15)
				(type solid)
			)
			(layer "F.Fab")
		)
		(fp_text user "${REFERENCE}"
			(at -0.939 4.599 270)
			(layer "F.Fab")
			(effects
				(font
					(size 0.7 0.7)
					(thickness 0.15)
				)
				(justify left bottom)
			)
		)
		(fp_text user "License: Apache-2.0"
			(at -0.939 5.799 270)
			(layer "F.Fab")
			(effects
				(font
					(size 0.7 0.7)
					(thickness 0.15)
				)
				(justify left bottom)
			)
		)
		(fp_text user "Author: Antmicro"
			(at -0.939 3.399 270)
			(layer "F.Fab")
			(effects
				(font
					(size 0.7 0.7)
					(thickness 0.15)
				)
				(justify left bottom)
			)
		)
		(pad "1" smd roundrect
			(at -0.48 0 270)
			(size 0.59 0.64)
			(layers "F.Cu" "F.Mask" "F.Paste")
			(roundrect_rratio 0.25)
			(net 31 "/USB/VREGIN")
			(pintype "passive")
		)
		(pad "2" smd roundrect
			(at 0.48 0 270)
			(size 0.59 0.64)
			(layers "F.Cu" "F.Mask" "F.Paste")
			(roundrect_rratio 0.25)
			(net 3 "GND")
			(pintype "passive")
		)
	)
	(footprint "antmicro-footprints:TP_SMD_0.75mm"
		(layer "F.Cu")
		(at 74.817962 162.0165 -90)
		(property "Reference" "TP309"
			(at 1.36 -0.39 0)
			(layer "F.SilkS")
			(effects
				(font
					(size 0.7 0.7)
					(thickness 0.15)
				)
				(justify right bottom)
			)
		)
		(property "Value" "TP_0.75mm_SMD"
			(at 0 1.2 90)
			(layer "F.Fab")
			(effects
				(font
					(size 0.7 0.7)
					(thickness 0.15)
				)
				(justify right bottom)
			)
		)
		(property "MPN" ""
			(at 0 0 270)
			(unlocked yes)
			(layer "F.Fab")
			(hide yes)
			(effects
				(font
					(size 1 1)
					(thickness 0.15)
				)
			)
		)
		(property "Manufacturer" ""
			(at 0 0 270)
			(unlocked yes)
			(layer "F.Fab")
			(hide yes)
			(effects
				(font
					(size 1 1)
					(thickness 0.15)
				)
			)
		)
		(property "Author" "Antmicro"
			(at 0 0 270)
			(unlocked yes)
			(layer "F.Fab")
			(hide yes)
			(effects
				(font
					(size 1 1)
					(thickness 0.15)
				)
			)
		)
		(property "License" "Apache-2.0"
			(at 0 0 270)
			(unlocked yes)
			(layer "F.Fab")
			(hide yes)
			(effects
				(font
					(size 1 1)
					(thickness 0.15)
				)
			)
		)
		(sheetname "/Supply/")
		(sheetfile "supply.kicad_sch")
		(attr exclude_from_pos_files exclude_from_bom)
		(fp_circle
			(center 0 0)
			(end 0.475 0)
			(stroke
				(width 0.05)
				(type default)
			)
			(fill no)
			(layer "F.CrtYd")
		)
		(fp_text user "Author: Antmicro"
			(at -0.4 3.901 270)
			(layer "F.Fab")
			(effects
				(font
					(size 0.7 0.7)
					(thickness 0.15)
				)
				(justify left bottom)
			)
		)
		(fp_text user "License: Apache-2.0"
			(at -0.4 5.101 270)
			(layer "F.Fab")
			(effects
				(font
					(size 0.7 0.7)
					(thickness 0.15)
				)
				(justify left bottom)
			)
		)
		(fp_text user "${REFERENCE}"
			(at -0.4 2.7 270)
			(layer "F.Fab")
			(effects
				(font
					(size 0.7 0.7)
					(thickness 0.15)
				)
				(justify left bottom)
			)
		)
		(pad "1" smd circle
			(at 0 0 270)
			(size 0.75 0.75)
			(layers "F.Cu" "F.Mask")
			(net 9 "+3V3")
			(pinfunction "1")
			(pintype "passive")
		)
	)
	(footprint "antmicro-footprints:C_0402_1005Metric"
		(layer "F.Cu")
		(at 62.117962 175.7255 -90)
		(descr "Capacitor SMD 0402")
		(tags "capacitor SMD 0402")
		(property "Reference" "C825"
			(at -3.579 14.88 90)
			(layer "F.SilkS")
			(effects
				(font
					(size 0.7 0.7)
					(thickness 0.15)
				)
				(justify right bottom)
			)
		)
		(property "Value" "C_39p_0402"
			(at -1.022927 2.155213 90)
			(layer "F.Fab")
			(effects
				(font
					(size 0.7 0.7)
					(thickness 0.15)
				)
				(justify right bottom)
			)
		)
		(property "Datasheet" "https://spicat.kyocera-avx.com/product/mlcc/chartview/04025A390JAT2A/"
			(at 0 0 270)
			(layer "F.Fab")
			(hide yes)
			(effects
				(font
					(size 1.27 1.27)
					(thickness 0.15)
				)
			)
		)
		(property "Description" "SMD Multilayer Ceramic Capacitor, 39 pF, 50 V, 0402 [1005 Metric], ± 5%, C0G / NP0, AVX 0402 MLCC"
			(at 0 0 270)
			(layer "F.Fab")
			(hide yes)
			(effects
				(font
					(size 1.27 1.27)
					(thickness 0.15)
				)
			)
		)
		(property "MPN" "04025A390JAT2A"
			(at 0 0 270)
			(unlocked yes)
			(layer "F.Fab")
			(hide yes)
			(effects
				(font
					(size 1 1)
					(thickness 0.15)
				)
			)
		)
		(property "Manufacturer" "KYOCERA AVX"
			(at 0 0 270)
			(unlocked yes)
			(layer "F.Fab")
			(hide yes)
			(effects
				(font
					(size 1 1)
					(thickness 0.15)
				)
			)
		)
		(property "License" "Apache-2.0"
			(at 0 0 270)
			(unlocked yes)
			(layer "F.Fab")
			(hide yes)
			(effects
				(font
					(size 1 1)
					(thickness 0.15)
				)
			)
		)
		(property "Author" "Antmicro"
			(at 0 0 270)
			(unlocked yes)
			(layer "F.Fab")
			(hide yes)
			(effects
				(font
					(size 1 1)
					(thickness 0.15)
				)
			)
		)
		(property "Val" "39p"
			(at 0 0 270)
			(unlocked yes)
			(layer "F.Fab")
			(hide yes)
			(effects
				(font
					(size 1 1)
					(thickness 0.15)
				)
			)
		)
		(property "Voltage" ""
			(at 0 0 270)
			(unlocked yes)
			(layer "F.Fab")
			(hide yes)
			(effects
				(font
					(size 1 1)
					(thickness 0.15)
				)
			)
		)
		(property "Dielectric" ""
			(at 0 0 270)
			(unlocked yes)
			(layer "F.Fab")
			(hide yes)
			(effects
				(font
					(size 1 1)
					(thickness 0.15)
				)
			)
		)
		(sheetname "/Peripherals/")
		(sheetfile "peripherals.kicad_sch")
		(attr smd)
		(fp_rect
			(start -0.925 -0.47)
			(end 0.925 0.47)
			(stroke
				(width 0.05)
				(type default)
			)
			(fill no)
			(layer "F.CrtYd")
		)
		(fp_line
			(start -0.494 0.248)
			(end -0.494 -0.25)
			(stroke
				(width 0.15)
				(type solid)
			)
			(layer "F.Fab")
		)
		(fp_line
			(start 0.504 0.248)
			(end -0.494 0.248)
			(stroke
				(width 0.15)
				(type solid)
			)
			(layer "F.Fab")
		)
		(fp_line
			(start -0.494 -0.25)
			(end 0.504 -0.25)
			(stroke
				(width 0.15)
				(type solid)
			)
			(layer "F.Fab")
		)
		(fp_line
			(start 0.504 -0.25)
			(end 0.504 0.248)
			(stroke
				(width 0.15)
				(type solid)
			)
			(layer "F.Fab")
		)
		(fp_text user "License: Apache-2.0"
			(at -0.939 5.799 270)
			(layer "F.Fab")
			(effects
				(font
					(size 0.7 0.7)
					(thickness 0.15)
				)
				(justify left bottom)
			)
		)
		(fp_text user "${REFERENCE}"
			(at -0.939 4.599 270)
			(layer "F.Fab")
			(effects
				(font
					(size 0.7 0.7)
					(thickness 0.15)
				)
				(justify left bottom)
			)
		)
		(fp_text user "Author: Antmicro"
			(at -0.939 3.399 270)
			(layer "F.Fab")
			(effects
				(font
					(size 0.7 0.7)
					(thickness 0.15)
				)
				(justify left bottom)
			)
		)
		(pad "1" smd roundrect
			(at -0.48 0 270)
			(size 0.59 0.64)
			(layers "F.Cu" "F.Mask" "F.Paste")
			(roundrect_rratio 0.25)
			(net 106 "Net-(C814-Pad2)")
			(pintype "passive")
		)
		(pad "2" smd roundrect
			(at 0.48 0 270)
			(size 0.59 0.64)
			(layers "F.Cu" "F.Mask" "F.Paste")
			(roundrect_rratio 0.25)
			(net 3 "GND")
			(pintype "passive")
		)
	)
)
